FILE_TYPE = CONNECTIVITY;
{Allegro Design Entry HDL 16.6-p007 (v16-6-112F) 10/10/2012}
"PAGE_NUMBER" = 36;
0"NC";
1"PVCCMCP_CPU0\g";
2"PVCCMCP_CPU0\g";
3"PVCCMCP_CPU0\g";
4"TP_CPU0_RSVD_113";
5"TP_CPU0_RSVD_144";
6"TP_CPU0_RSVD_145";
7"TP_CPU0_RSVD_146";
8"TP_CPU0_RSVD_147";
9"TP_CPU0_RSVD_148";
10"TP_CPU0_RSVD_149";
11"TP_CPU0_RSVD_150";
12"TP_CPU0_RSVD_151";
13"TP_CPU0_RSVD_152";
14"TP_CPU0_RSVD_154";
15"TP_CPU0_RSVD_155";
16"TP_CPU0_RSVD_156";
17"TP_CPU0_RSVD_157";
18"TP_CPU0_RSVD_158";
19"TP_CPU0_RSVD_159";
20"TP_CPU0_RSVD_160";
21"TP_CPU0_RSVD_161";
22"TP_CPU0_RSVD_162";
23"TP_CPU0_RSVD_163";
24"TP_CPU0_RSVD_164";
25"TP_CPU0_RSVD_166";
26"TP_CPU0_RSVD_167";
27"TP_CPU0_RSVD_168";
28"TP_CPU0_RSVD_169";
29"TP_CPU0_RSVD_170";
30"TP_CPU0_RSVD_171";
31"CLK_100M_CPU0_RC_REFCLK1_DP";
32"CLK_100M_CPU0_RC_REFCLK1_DN";
33"TP_CPU0_RSVD_255";
34"TP_CPU0_RSVD_94";
35"TP_CPU0_RSVD_95";
36"TP_CPU0_RSVD_97";
37"TP_CPU0_RSVD_99";
38"TP_CPU0_RSVD_100";
39"TP_CPU0_RSVD_101";
40"TP_CPU0_RSVD_105";
41"TP_CPU0_RSVD_106";
42"TP_CPU0_RSVD_108";
43"TP_CPU0_RSVD_111";
44"TP_CPU0_RSVD_114";
45"TP_CPU0_RSVD_117";
46"TP_CPU0_RSVD_119";
47"TP_CPU0_RSVD_121";
48"TP_CPU0_RSVD_123";
49"TP_CPU0_RSVD_124";
50"TP_CPU0_TEST_9";
51"TP_CPU0_TEST_8";
52"TP_CPU0_TEST_7";
53"TP_CPU0_TEST_6";
54"TP_CPU0_TEST_10";
55"TP_CPU0_RSVD_82";
56"TP_CPU0_RSVD_85";
57"TP_CPU0_RSVD_90";
58"TP_CPU0_RSVD_91";
%"VCC_CORE"
"1","(-4500,3800)","0","mstr_symbols","I12";
;
CDS_LIB"mstr_symbols"
HDL_POWER"PVCCMCP_CPU0";
"A"1;
%"VCC_CORE"
"1","(-925,2700)","0","mstr_symbols","I13";
;
CDS_LIB"mstr_symbols"
HDL_POWER"PVCCMCP_CPU0";
"A"2;
%"VCC_CORE"
"1","(-7850,2350)","0","mstr_symbols","I14";
;
CDS_LIB"mstr_symbols"
HDL_POWER"PVCCMCP_CPU0";
"A"3;
%"SKX_EXT_B"
"16","(-6075,2550)","0","chpset_lib","I15";
;
CDS_SEC"16"
ROOM"CPU0"
CDS_LOCATION"U5D1"
SEC"16"
CDS_LIB"chpset_lib"
SEC_TYPE"BGA1"
PACK_TYPE"BGA1"
MATERIAL"IC"
PART_NUMBER"TBD"
LOCATION"U5D1";
"RSVD<92>"
$PN"CH23"1;
"RSVD<93>"
$PN"CH21"1;
"RSVD<94>"
$PN"CG82"34;
"RSVD<95>"
$PN"CG78"35;
"RSVD<96>"
$PN"CG26"1;
"RSVD<97>"
$PN"CG24"36;
"RSVD<98>"
$PN"CG20"1;
"RSVD<99>"
$PN"CG10"37;
"RSVD<100>"
$PN"CF81"38;
"RSVD<101>"
$PN"CF79"39;
"RSVD<102>"
$PN"CF23"1;
"RSVD<103>"
$PN"CF21"1;
"RSVD<104>"
$PN"CF19"1;
"RSVD<105>"
$PN"CE80"40;
"RSVD<106>"
$PN"CE78"41;
"RSVD<107>"
$PN"CE22"1;
"RSVD<108>"
$PN"CD25"42;
"RSVD<109>"
$PN"CD21"1;
"RSVD<110>"
$PN"CD19"1;
"RSVD<111>"
$PN"CC6"43;
"RSVD<112>"
$PN"CC20"1;
"RSVD<113>"
$PN"CB5"4;
"RSVD<114>"
$PN"CB25"44;
"RSVD<115>"
$PN"CB21"1;
"RSVD<116>"
$PN"CB19"1;
"RSVD<117>"
$PN"CA24"45;
"RSVD<118>"
$PN"CA22"1;
"RSVD<119>"
$PN"BY25"46;
"RSVD<120>"
$PN"BY19"1;
"RSVD<121>"
$PN"BW22"47;
"RSVD<122>"
$PN"BW20"1;
"RSVD<123>"
$PN"BW10"48;
"RSVD<124>"
$PN"BV23"49;
"RSVD<125>"
$PN"BV21"1;
"RSVD<126>"
$PN"BV19"1;
"RSVD<127>"
$PN"BU22"3;
"RSVD<128>"
$PN"BU20"3;
"RSVD<129>"
$PN"BU18"3;
"RSVD<130>"
$PN"BR24"3;
"RSVD<131>"
$PN"BR22"3;
"RSVD<132>"
$PN"BP21"3;
"RSVD<133>"
$PN"BP17"3;
"RSVD<134>"
$PN"BN18"3;
"RSVD<135>"
$PN"BM19"3;
"RSVD<136>"
$PN"BM17"3;
"RSVD<137>"
$PN"BL20"3;
"RSVD<138>"
$PN"BL18"3;
"RSVD<139>"
$PN"BK17"3;
"RSVD<140>"
$PN"BJ20"3;
"RSVD<141>"
$PN"BJ18"3;
"RSVD<142>"
$PN"BJ16"3;
"RSVD<143>"
$PN"BH19"3;
"RSVD<144>"
$PN"BG20"5;
"RSVD<145>"
$PN"BG18"6;
"RSVD<146>"
$PN"BF21"7;
"RSVD<147>"
$PN"BE22"8;
"RSVD<148>"
$PN"BE20"9;
"RSVD<149>"
$PN"BE18"10;
"RSVD<150>"
$PN"BD69"11;
"RSVD<151>"
$PN"BD67"12;
"RSVD<152>"
$PN"BD65"13;
"RSVD<153>"
$PN"BD25"31;
"RSVD<154>"
$PN"BD19"14;
"RSVD<155>"
$PN"BD17"15;
"RSVD<156>"
$PN"BC68"16;
"RSVD<157>"
$PN"BC66"17;
"RSVD<158>"
$PN"BC64"18;
"RSVD<159>"
$PN"BC22"19;
"RSVD<160>"
$PN"BC20"20;
"RSVD<161>"
$PN"BC18"21;
"RSVD<162>"
$PN"BC14"22;
"RSVD<163>"
$PN"BB67"23;
"RSVD<164>"
$PN"BB65"24;
"RSVD<165>"
$PN"BB25"32;
"RSVD<166>"
$PN"BB21"25;
"RSVD<167>"
$PN"BB17"26;
"RSVD<168>"
$PN"BB15"27;
"RSVD<169>"
$PN"BB13"28;
"RSVD<170>"
$PN"BA82"29;
"RSVD<171>"
$PN"BA78"30;
"RSVD<255>"
$PN"AY83"33;
%"SKX_EXT_B"
"17","(-2550,2525)","0","chpset_lib","I16";
;
CDS_SEC"17"
ROOM"CPU0"
CDS_LOCATION"U5D1"
SEC"17"
CDS_LIB"chpset_lib"
SEC_TYPE"BGA1"
PACK_TYPE"BGA1"
MATERIAL"IC"
PART_NUMBER"TBD"
LOCATION"U5D1";
"TEST_9"
$PN"AW20"50;
"TEST_8"
$PN"AW16"51;
"TEST_7"
$PN"AU18"52;
"TEST_6"
$PN"AR16"53;
"TEST_10"
$PN"AW22"54;
"RSVD<81>"
$PN"CL24"2;
"RSVD<82>"
$PN"CK77"55;
"RSVD<83>"
$PN"CK25"2;
"RSVD<84>"
$PN"CK23"2;
"RSVD<85>"
$PN"CK19"56;
"RSVD<86>"
$PN"CJ26"2;
"RSVD<87>"
$PN"CJ24"2;
"RSVD<88>"
$PN"CJ22"2;
"RSVD<89>"
$PN"CJ20"2;
"RSVD<90>"
$PN"CH77"57;
"RSVD<91>"
$PN"CH25"58;
END.
